(kicad_pcb
	(version 20260206)
	(generator "pcbnew")
	(generator_version "10.0")
	(general
		(thickness 1.6)
		(legacy_teardrops no)
	)
	(paper "A4")
	(title_block
		(title "Bryce Canyon_SCC_16316-1_OCP.brd")
		(comment 1 "Bryce Canyon / footprints 30-36 of 1561")
	)
	(layers
		(0 "F.Cu" signal "TOP")
		(4 "In1.Cu" signal "L2GND")
		(6 "In2.Cu" signal "L3")
		(8 "In3.Cu" signal "L4VCC")
		(10 "In4.Cu" signal "L5VCC")
		(12 "In5.Cu" signal "L6")
		(14 "In6.Cu" signal "L7GND")
		(2 "B.Cu" signal "BOTTOM")
		(9 "F.Adhes" user "F.Adhesive")
		(11 "B.Adhes" user "B.Adhesive")
		(13 "F.Paste" user "Package Geometry/Pastemask Top")
		(15 "B.Paste" user "Package Geometry/Pastemask Bottom")
		(5 "F.SilkS" user "Ref Des/Silkscreen Top")
		(7 "B.SilkS" user "Ref Des/Silkscreen Bottom")
		(1 "F.Mask" user "Board Geometry/Soldermask Top")
		(3 "B.Mask" user "Board Geometry/Soldermask Bottom")
		(17 "Dwgs.User" user "User.Drawings")
		(19 "Cmts.User" user "User.Comments")
		(21 "Eco1.User" user "User.Eco1")
		(23 "Eco2.User" user "User.Eco2")
		(25 "Edge.Cuts" user "Board Geometry/Outline")
		(27 "Margin" user)
		(31 "F.CrtYd" user "Package Geometry/Place Bound Top")
		(29 "B.CrtYd" user "Package Geometry/Place Bound Bottom")
		(35 "F.Fab" user "Ref Des/Assembly Top")
		(33 "B.Fab" user "Ref Des/Assembly Bottom")
	)
	(footprint ""
		(layer "F.Cu")
		(at 199.78624 -82.91322)
		(property "Reference" "C577"
			(at 0 0 0)
			(layer "F.SilkS")
			(hide yes)
			(effects
				(font
					(size 1.27 1.27)
				)
			)
		)
		(property "Value" "SCD1U16V2KX-3GP"
			(at 1.1811 -2.7051 0)
			(unlocked yes)
			(layer "F.Fab")
			(hide yes)
			(effects
				(font
					(size 1.016 1.016)
					(thickness 0.1524)
				)
			)
		)
		(property "Device Type" "C402H22"
			(at 1.1811 -4.2291 0)
			(unlocked yes)
			(layer "F.Fab")
			(hide yes)
			(effects
				(font
					(size 1.016 1.016)
					(thickness 0.1524)
				)
			)
		)
		(duplicate_pad_numbers_are_jumpers no)
		(fp_rect
			(start -0.4318 0.9525)
			(end 0.4318 -0.9525)
			(stroke
				(width 0)
				(type default)
			)
			(fill no)
			(layer "F.CrtYd")
		)
		(fp_rect
			(start -0.4318 0.9525)
			(end 0.4318 -0.9525)
			(stroke
				(width 0)
				(type default)
			)
			(fill no)
			(layer "F.Fab")
		)
		(pad "1" smd custom
			(at 0 -0.4445)
			(size 0.1524 0.1524)
			(layers "F.Cu" "F.Mask" "F.Paste")
			(net "SDB_CONN_PWR_3")
			(options
				(clearance outline)
				(anchor circle)
			)
			(primitives
				(gr_poly
					(pts
						(arc
							(start 0.3048 -0.2032)
							(mid 0.275042 -0.275042)
							(end 0.2032 -0.3048)
						)
						(arc
							(start -0.2032 -0.3048)
							(mid -0.275042 -0.275042)
							(end -0.3048 -0.2032)
						)
						(arc
							(start -0.3048 0.2032)
							(mid -0.275042 0.275042)
							(end -0.2032 0.3048)
						)
						(arc
							(start 0.2032 0.3048)
							(mid 0.275042 0.275042)
							(end 0.3048 0.2032)
						)
					)
					(width 0)
					(fill yes)
				)
			)
		)
		(pad "2" smd custom
			(at 0 0.4445)
			(size 0.1524 0.1524)
			(layers "F.Cu" "F.Mask" "F.Paste")
			(net "GND")
			(options
				(clearance outline)
				(anchor circle)
			)
			(primitives
				(gr_poly
					(pts
						(arc
							(start 0.3048 -0.2032)
							(mid 0.275042 -0.275042)
							(end 0.2032 -0.3048)
						)
						(arc
							(start -0.2032 -0.3048)
							(mid -0.275042 -0.275042)
							(end -0.3048 -0.2032)
						)
						(arc
							(start -0.3048 0.2032)
							(mid -0.275042 0.275042)
							(end -0.2032 0.3048)
						)
						(arc
							(start 0.2032 0.3048)
							(mid 0.275042 0.275042)
							(end 0.3048 0.2032)
						)
					)
					(width 0)
					(fill yes)
				)
			)
		)
	)
	(footprint ""
		(layer "F.Cu")
		(at 13.335 -72.3138 -90)
		(property "Reference" "U29"
			(at 0 0 270)
			(layer "F.SilkS")
			(hide yes)
			(effects
				(font
					(size 1.27 1.27)
				)
			)
		)
		(property "Value" "24LC64-I-SN-1-GP"
			(at -3.707384 -1.5367 270)
			(unlocked yes)
			(layer "F.Fab")
			(hide yes)
			(effects
				(font
					(size 1.016 1.016)
					(thickness 0.1524)
				)
			)
		)
		(property "Device Type" "SOIC8H69"
			(at -3.707384 -3.0607 270)
			(unlocked yes)
			(layer "F.Fab")
			(hide yes)
			(effects
				(font
					(size 1.016 1.016)
					(thickness 0.1524)
				)
			)
		)
		(duplicate_pad_numbers_are_jumpers no)
		(fp_line
			(start -2.6289 3.4417)
			(end -2.6289 1.4732)
			(stroke
				(width 0.381)
				(type default)
			)
			(layer "F.SilkS")
		)
		(fp_line
			(start -2.7432 1.4224)
			(end -2.6416 1.4224)
			(stroke
				(width 0.1524)
				(type default)
			)
			(layer "F.SilkS")
		)
		(fp_line
			(start -2.7432 1.4224)
			(end 2.1336 1.4224)
			(stroke
				(width 0.1524)
				(type default)
			)
			(layer "F.SilkS")
		)
		(fp_line
			(start 2.1336 1.4224)
			(end 2.1336 -1.4224)
			(stroke
				(width 0.1524)
				(type default)
			)
			(layer "F.SilkS")
		)
		(fp_line
			(start -2.1844 -0.0508)
			(end -2.7178 0.508)
			(stroke
				(width 0.1524)
				(type default)
			)
			(layer "F.SilkS")
		)
		(fp_line
			(start -2.7178 -0.508)
			(end -2.1844 -0.0508)
			(stroke
				(width 0.1524)
				(type default)
			)
			(layer "F.SilkS")
		)
		(fp_line
			(start -2.7432 -1.4224)
			(end -2.7432 1.4224)
			(stroke
				(width 0.1524)
				(type default)
			)
			(layer "F.SilkS")
		)
		(fp_line
			(start 2.1336 -1.4224)
			(end -2.7432 -1.4224)
			(stroke
				(width 0.1524)
				(type default)
			)
			(layer "F.SilkS")
		)
		(fp_poly
			(pts
				(xy -2.2098 -1.4224) (xy -2.2098 1.4224) (xy 2.2098 1.4224) (xy 2.2098 -1.4224)
			)
			(stroke
				(width 0)
				(type default)
			)
			(fill yes)
			(layer "F.SilkS")
		)
		(fp_rect
			(start -2.450084 2.999994)
			(end 2.450084 -2.999994)
			(stroke
				(width 0)
				(type default)
			)
			(fill no)
			(layer "F.CrtYd")
		)
		(fp_poly
			(pts
				(xy -2.8194 3.6322) (xy -2.8194 -3.6322) (xy 2.8194 -3.6322) (xy 2.8194 1.18364) (xy 2.450084 1.18364)
				(xy 2.450084 -2.999994) (xy -2.450084 -2.999994) (xy -2.450084 2.999994) (xy 2.450084 2.999994)
				(xy 2.450084 1.18618) (xy 2.8194 1.18618) (xy 2.8194 3.6322)
			)
			(stroke
				(width 0)
				(type default)
			)
			(fill no)
			(layer "F.CrtYd")
		)
		(fp_rect
			(start -2.8194 3.6322)
			(end 2.8194 -3.6322)
			(stroke
				(width 0)
				(type default)
			)
			(fill no)
			(layer "F.Fab")
		)
		(pad "1" smd rect
			(at -1.905 2.54 270)
			(size 0.635 1.651)
			(layers "F.Cu" "F.Mask" "F.Paste")
			(net "FRU_EEPROM_A0")
		)
		(pad "2" smd rect
			(at -0.635 2.54 270)
			(size 0.635 1.651)
			(layers "F.Cu" "F.Mask" "F.Paste")
			(net "FRU_EEPROM_A1")
		)
		(pad "3" smd rect
			(at 0.635 2.54 270)
			(size 0.635 1.651)
			(layers "F.Cu" "F.Mask" "F.Paste")
			(net "FRU_EEPROM_A2")
		)
		(pad "4" smd rect
			(at 1.905 2.54 270)
			(size 0.635 1.651)
			(layers "F.Cu" "F.Mask" "F.Paste")
			(net "GND")
		)
		(pad "5" smd rect
			(at 1.905 -2.54 270)
			(size 0.635 1.651)
			(layers "F.Cu" "F.Mask" "F.Paste")
			(net "EEPROM_SDA")
		)
		(pad "6" smd rect
			(at 0.635 -2.54 270)
			(size 0.635 1.651)
			(layers "F.Cu" "F.Mask" "F.Paste")
			(net "EEPROM_SCL")
		)
		(pad "7" smd rect
			(at -0.635 -2.54 270)
			(size 0.635 1.651)
			(layers "F.Cu" "F.Mask" "F.Paste")
			(net "EEPROM_WP")
		)
		(pad "8" smd rect
			(at -1.905 -2.54 270)
			(size 0.635 1.651)
			(layers "F.Cu" "F.Mask" "F.Paste")
			(net "P3V3")
		)
	)
	(footprint ""
		(layer "F.Cu")
		(at 155.8417 -80.007714 -90)
		(property "Reference" "R334"
			(at 0 0 270)
			(layer "F.SilkS")
			(hide yes)
			(effects
				(font
					(size 1.27 1.27)
				)
			)
		)
		(property "Value" "4K7R2F-GP"
			(at 0.064008 -3.993896 270)
			(unlocked yes)
			(layer "F.Fab")
			(hide yes)
			(effects
				(font
					(size 1.016 1.016)
					(thickness 0.1524)
				)
			)
		)
		(property "Device Type" "R402H16"
			(at 0.064008 -5.517896 270)
			(unlocked yes)
			(layer "F.Fab")
			(hide yes)
			(effects
				(font
					(size 1.016 1.016)
					(thickness 0.1524)
				)
			)
		)
		(duplicate_pad_numbers_are_jumpers no)
		(fp_line
			(start -0.508 -0.9398)
			(end -0.508 0.9398)
			(stroke
				(width 0.1524)
				(type default)
			)
			(layer "F.SilkS")
		)
		(fp_line
			(start 0.508 -0.9398)
			(end -0.508 -0.9398)
			(stroke
				(width 0.1524)
				(type default)
			)
			(layer "F.SilkS")
		)
		(fp_rect
			(start -0.508 0.9398)
			(end 0.508 -0.9398)
			(stroke
				(width 0)
				(type default)
			)
			(fill no)
			(layer "F.CrtYd")
		)
		(fp_rect
			(start -0.508 0.9398)
			(end 0.508 -0.9398)
			(stroke
				(width 0)
				(type default)
			)
			(fill no)
			(layer "F.Fab")
		)
		(pad "1" smd custom
			(at 0 -0.4445 270)
			(size 0.1397 0.1397)
			(layers "F.Cu" "F.Mask" "F.Paste")
			(net "VOL_SEN2_ADDR")
			(options
				(clearance outline)
				(anchor circle)
			)
			(primitives
				(gr_poly
					(pts
						(arc
							(start -0.1778 -0.2794)
							(mid -0.249642 -0.249642)
							(end -0.2794 -0.1778)
						)
						(arc
							(start -0.2794 0.1778)
							(mid -0.249642 0.249642)
							(end -0.1778 0.2794)
						)
						(arc
							(start 0.1778 0.2794)
							(mid 0.249642 0.249642)
							(end 0.2794 0.1778)
						)
						(arc
							(start 0.2794 -0.1778)
							(mid 0.249642 -0.249642)
							(end 0.1778 -0.2794)
						)
					)
					(width 0)
					(fill yes)
				)
			)
		)
		(pad "2" smd custom
			(at 0 0.4445 270)
			(size 0.1397 0.1397)
			(layers "F.Cu" "F.Mask" "F.Paste")
			(net "GND")
			(options
				(clearance outline)
				(anchor circle)
			)
			(primitives
				(gr_poly
					(pts
						(arc
							(start -0.1778 -0.2794)
							(mid -0.249642 -0.249642)
							(end -0.2794 -0.1778)
						)
						(arc
							(start -0.2794 0.1778)
							(mid -0.249642 0.249642)
							(end -0.1778 0.2794)
						)
						(arc
							(start 0.1778 0.2794)
							(mid 0.249642 0.249642)
							(end 0.2794 0.1778)
						)
						(arc
							(start 0.2794 -0.1778)
							(mid 0.249642 -0.249642)
							(end 0.1778 -0.2794)
						)
					)
					(width 0)
					(fill yes)
				)
			)
		)
	)
	(footprint ""
		(layer "F.Cu")
		(at 187.3758 -21.8948 -90)
		(property "Reference" "R272"
			(at 0 0 270)
			(layer "F.SilkS")
			(hide yes)
			(effects
				(font
					(size 1.27 1.27)
				)
			)
		)
		(property "Value" "10KR2F-2-GP"
			(at 0.064008 -3.993896 270)
			(unlocked yes)
			(layer "F.Fab")
			(hide yes)
			(effects
				(font
					(size 1.016 1.016)
					(thickness 0.1524)
				)
			)
		)
		(property "Device Type" "R402H16"
			(at 0.064008 -5.517896 270)
			(unlocked yes)
			(layer "F.Fab")
			(hide yes)
			(effects
				(font
					(size 1.016 1.016)
					(thickness 0.1524)
				)
			)
		)
		(duplicate_pad_numbers_are_jumpers no)
		(fp_line
			(start -0.508 -0.9398)
			(end -0.508 0.9398)
			(stroke
				(width 0.1524)
				(type default)
			)
			(layer "F.SilkS")
		)
		(fp_line
			(start 0.508 -0.9398)
			(end -0.508 -0.9398)
			(stroke
				(width 0.1524)
				(type default)
			)
			(layer "F.SilkS")
		)
		(fp_rect
			(start -0.508 0.9398)
			(end 0.508 -0.9398)
			(stroke
				(width 0)
				(type default)
			)
			(fill no)
			(layer "F.CrtYd")
		)
		(fp_rect
			(start -0.508 0.9398)
			(end 0.508 -0.9398)
			(stroke
				(width 0)
				(type default)
			)
			(fill no)
			(layer "F.Fab")
		)
		(pad "1" smd custom
			(at 0 -0.4445 270)
			(size 0.1397 0.1397)
			(layers "F.Cu" "F.Mask" "F.Paste")
			(net "SYS_DBMODE1")
			(options
				(clearance outline)
				(anchor circle)
			)
			(primitives
				(gr_poly
					(pts
						(arc
							(start -0.1778 -0.2794)
							(mid -0.249642 -0.249642)
							(end -0.2794 -0.1778)
						)
						(arc
							(start -0.2794 0.1778)
							(mid -0.249642 0.249642)
							(end -0.1778 0.2794)
						)
						(arc
							(start 0.1778 0.2794)
							(mid 0.249642 0.249642)
							(end 0.2794 0.1778)
						)
						(arc
							(start 0.2794 -0.1778)
							(mid 0.249642 -0.249642)
							(end 0.1778 -0.2794)
						)
					)
					(width 0)
					(fill yes)
				)
			)
		)
		(pad "2" smd custom
			(at 0 0.4445 270)
			(size 0.1397 0.1397)
			(layers "F.Cu" "F.Mask" "F.Paste")
			(net "GND")
			(options
				(clearance outline)
				(anchor circle)
			)
			(primitives
				(gr_poly
					(pts
						(arc
							(start -0.1778 -0.2794)
							(mid -0.249642 -0.249642)
							(end -0.2794 -0.1778)
						)
						(arc
							(start -0.2794 0.1778)
							(mid -0.249642 0.249642)
							(end -0.1778 0.2794)
						)
						(arc
							(start 0.1778 0.2794)
							(mid 0.249642 0.249642)
							(end 0.2794 0.1778)
						)
						(arc
							(start 0.2794 -0.1778)
							(mid 0.249642 -0.249642)
							(end 0.1778 -0.2794)
						)
					)
					(width 0)
					(fill yes)
				)
			)
		)
	)
	(footprint ""
		(layer "F.Cu")
		(at 193.0908 -34.3916 -90)
		(property "Reference" "R181"
			(at 0 0 270)
			(layer "F.SilkS")
			(hide yes)
			(effects
				(font
					(size 1.27 1.27)
				)
			)
		)
		(property "Value" "2K2R2F-GP"
			(at 0.064008 -3.993896 270)
			(unlocked yes)
			(layer "F.Fab")
			(hide yes)
			(effects
				(font
					(size 1.016 1.016)
					(thickness 0.1524)
				)
			)
		)
		(property "Device Type" "R402H16"
			(at 0.064008 -5.517896 270)
			(unlocked yes)
			(layer "F.Fab")
			(hide yes)
			(effects
				(font
					(size 1.016 1.016)
					(thickness 0.1524)
				)
			)
		)
		(duplicate_pad_numbers_are_jumpers no)
		(fp_line
			(start -0.508 -0.9398)
			(end -0.508 0.9398)
			(stroke
				(width 0.1524)
				(type default)
			)
			(layer "F.SilkS")
		)
		(fp_line
			(start 0.508 -0.9398)
			(end -0.508 -0.9398)
			(stroke
				(width 0.1524)
				(type default)
			)
			(layer "F.SilkS")
		)
		(fp_rect
			(start -0.508 0.9398)
			(end 0.508 -0.9398)
			(stroke
				(width 0)
				(type default)
			)
			(fill no)
			(layer "F.CrtYd")
		)
		(fp_rect
			(start -0.508 0.9398)
			(end 0.508 -0.9398)
			(stroke
				(width 0)
				(type default)
			)
			(fill no)
			(layer "F.Fab")
		)
		(pad "1" smd custom
			(at 0 -0.4445 270)
			(size 0.1397 0.1397)
			(layers "F.Cu" "F.Mask" "F.Paste")
			(net "P1V8_C")
			(options
				(clearance outline)
				(anchor circle)
			)
			(primitives
				(gr_poly
					(pts
						(arc
							(start -0.1778 -0.2794)
							(mid -0.249642 -0.249642)
							(end -0.2794 -0.1778)
						)
						(arc
							(start -0.2794 0.1778)
							(mid -0.249642 0.249642)
							(end -0.1778 0.2794)
						)
						(arc
							(start 0.1778 0.2794)
							(mid 0.249642 0.249642)
							(end 0.2794 0.1778)
						)
						(arc
							(start 0.2794 -0.1778)
							(mid 0.249642 -0.249642)
							(end 0.1778 -0.2794)
						)
					)
					(width 0)
					(fill yes)
				)
			)
		)
		(pad "2" smd custom
			(at 0 0.4445 270)
			(size 0.1397 0.1397)
			(layers "F.Cu" "F.Mask" "F.Paste")
			(net "I2C_IOC_0_SCL")
			(options
				(clearance outline)
				(anchor circle)
			)
			(primitives
				(gr_poly
					(pts
						(arc
							(start -0.1778 -0.2794)
							(mid -0.249642 -0.249642)
							(end -0.2794 -0.1778)
						)
						(arc
							(start -0.2794 0.1778)
							(mid -0.249642 0.249642)
							(end -0.1778 0.2794)
						)
						(arc
							(start 0.1778 0.2794)
							(mid 0.249642 0.249642)
							(end 0.2794 0.1778)
						)
						(arc
							(start 0.2794 -0.1778)
							(mid 0.249642 -0.249642)
							(end 0.1778 -0.2794)
						)
					)
					(width 0)
					(fill yes)
				)
			)
		)
	)
	(footprint ""
		(layer "F.Cu")
		(at 7.2898 -71.9328 90)
		(property "Reference" "R357"
			(at 0 0 90)
			(layer "F.SilkS")
			(hide yes)
			(effects
				(font
					(size 1.27 1.27)
				)
			)
		)
		(property "Value" "4K7R2F-GP"
			(at 0.064008 -3.993896 90)
			(unlocked yes)
			(layer "F.Fab")
			(hide yes)
			(effects
				(font
					(size 1.016 1.016)
					(thickness 0.1524)
				)
			)
		)
		(property "Device Type" "R402H16"
			(at 0.064008 -5.517896 90)
			(unlocked yes)
			(layer "F.Fab")
			(hide yes)
			(effects
				(font
					(size 1.016 1.016)
					(thickness 0.1524)
				)
			)
		)
		(duplicate_pad_numbers_are_jumpers no)
		(fp_line
			(start 0.508 -0.9398)
			(end -0.508 -0.9398)
			(stroke
				(width 0.1524)
				(type default)
			)
			(layer "F.SilkS")
		)
		(fp_line
			(start -0.508 -0.9398)
			(end -0.508 0.9398)
			(stroke
				(width 0.1524)
				(type default)
			)
			(layer "F.SilkS")
		)
		(fp_rect
			(start -0.508 0.9398)
			(end 0.508 -0.9398)
			(stroke
				(width 0)
				(type default)
			)
			(fill no)
			(layer "F.CrtYd")
		)
		(fp_rect
			(start -0.508 0.9398)
			(end 0.508 -0.9398)
			(stroke
				(width 0)
				(type default)
			)
			(fill no)
			(layer "F.Fab")
		)
		(pad "1" smd custom
			(at 0 -0.4445 90)
			(size 0.1397 0.1397)
			(layers "F.Cu" "F.Mask" "F.Paste")
			(net "P3V3")
			(options
				(clearance outline)
				(anchor circle)
			)
			(primitives
				(gr_poly
					(pts
						(arc
							(start -0.1778 -0.2794)
							(mid -0.249642 -0.249642)
							(end -0.2794 -0.1778)
						)
						(arc
							(start -0.2794 0.1778)
							(mid -0.249642 0.249642)
							(end -0.1778 0.2794)
						)
						(arc
							(start 0.1778 0.2794)
							(mid 0.249642 0.249642)
							(end 0.2794 0.1778)
						)
						(arc
							(start 0.2794 -0.1778)
							(mid 0.249642 -0.249642)
							(end 0.1778 -0.2794)
						)
					)
					(width 0)
					(fill yes)
				)
			)
		)
		(pad "2" smd custom
			(at 0 0.4445 90)
			(size 0.1397 0.1397)
			(layers "F.Cu" "F.Mask" "F.Paste")
			(net "FRU_EEPROM_A1")
			(options
				(clearance outline)
				(anchor circle)
			)
			(primitives
				(gr_poly
					(pts
						(arc
							(start -0.1778 -0.2794)
							(mid -0.249642 -0.249642)
							(end -0.2794 -0.1778)
						)
						(arc
							(start -0.2794 0.1778)
							(mid -0.249642 0.249642)
							(end -0.1778 0.2794)
						)
						(arc
							(start 0.1778 0.2794)
							(mid 0.249642 0.249642)
							(end 0.2794 0.1778)
						)
						(arc
							(start 0.2794 -0.1778)
							(mid 0.249642 -0.249642)
							(end 0.1778 -0.2794)
						)
					)
					(width 0)
					(fill yes)
				)
			)
		)
	)
	(footprint ""
		(layer "F.Cu")
		(at 126.110746 -44.74718 180)
		(property "Reference" "C48"
			(at 0 0 180)
			(layer "F.SilkS")
			(hide yes)
			(effects
				(font
					(size 1.27 1.27)
				)
			)
		)
		(property "Value" "SCD01U16V1KX-GP"
			(at -2.8321 -1.7399 180)
			(unlocked yes)
			(layer "F.Fab")
			(hide yes)
			(effects
				(font
					(size 1.016 1.016)
					(thickness 0.1524)
				)
			)
		)
		(property "Device Type" "C0201H13"
			(at -2.8321 -3.2639 180)
			(unlocked yes)
			(layer "F.Fab")
			(hide yes)
			(effects
				(font
					(size 1.016 1.016)
					(thickness 0.1524)
				)
			)
		)
		(duplicate_pad_numbers_are_jumpers no)
		(fp_rect
			(start -0.2794 0.6477)
			(end 0.2794 -0.6477)
			(stroke
				(width 0)
				(type default)
			)
			(fill no)
			(layer "F.CrtYd")
		)
		(fp_rect
			(start -0.2794 0.6477)
			(end 0.2794 -0.6477)
			(stroke
				(width 0)
				(type default)
			)
			(fill no)
			(layer "F.Fab")
		)
		(pad "1" smd custom
			(at 0 -0.2794 180)
			(size 0.0762 0.0762)
			(layers "F.Cu" "F.Mask" "F.Paste")
			(net "PHY_IOC_TO_SCC_40_DN")
			(options
				(clearance outline)
				(anchor circle)
			)
			(primitives
				(gr_poly
					(pts
						(arc
							(start 0.1524 -0.127)
							(mid 0.137521 -0.162921)
							(end 0.1016 -0.1778)
						)
						(arc
							(start -0.1016 -0.1778)
							(mid -0.137521 -0.162921)
							(end -0.1524 -0.127)
						)
						(arc
							(start -0.1524 0.127)
							(mid -0.137521 0.162921)
							(end -0.1016 0.1778)
						)
						(arc
							(start 0.1016 0.1778)
							(mid 0.137521 0.162921)
							(end 0.1524 0.127)
						)
					)
					(width 0)
					(fill yes)
				)
			)
		)
		(pad "2" smd custom
			(at 0 0.2794 180)
			(size 0.0762 0.0762)
			(layers "F.Cu" "F.Mask" "F.Paste")
			(net "PHY_IOC_TO_SCC_C_40_DN")
			(options
				(clearance outline)
				(anchor circle)
			)
			(primitives
				(gr_poly
					(pts
						(arc
							(start 0.1524 -0.127)
							(mid 0.137521 -0.162921)
							(end 0.1016 -0.1778)
						)
						(arc
							(start -0.1016 -0.1778)
							(mid -0.137521 -0.162921)
							(end -0.1524 -0.127)
						)
						(arc
							(start -0.1524 0.127)
							(mid -0.137521 0.162921)
							(end -0.1016 0.1778)
						)
						(arc
							(start 0.1016 0.1778)
							(mid 0.137521 0.162921)
							(end 0.1524 0.127)
						)
					)
					(width 0)
					(fill yes)
				)
			)
		)
	)
)
